(kicad_pcb
	(version 20260206)
	(generator "pcbnew")
	(generator_version "10.0")
	(general
		(thickness 1.6)
		(legacy_teardrops no)
	)
	(paper "A4")
	(title_block
		(title "dpb — 14545-sa.0730WZS0815.brd")
		(comment 1 "Honey Badger (Wiwynn) / footprints 939-946 of 1066")
	)
	(layers
		(0 "F.Cu" signal "TOP")
		(4 "In1.Cu" signal "L2GND")
		(6 "In2.Cu" signal "L3")
		(8 "In3.Cu" signal "L4VCC")
		(10 "In4.Cu" signal "L5VCC")
		(12 "In5.Cu" signal "L6")
		(14 "In6.Cu" signal "L7GND")
		(2 "B.Cu" signal "BOTTOM")
		(9 "F.Adhes" user "F.Adhesive")
		(11 "B.Adhes" user "B.Adhesive")
		(13 "F.Paste" user "Package Geometry/Pastemask Top")
		(15 "B.Paste" user "Package Geometry/Pastemask Bottom")
		(5 "F.SilkS" user "Ref Des/Silkscreen Top")
		(7 "B.SilkS" user "Ref Des/Silkscreen Bottom")
		(1 "F.Mask" user "Board Geometry/Soldermask Top")
		(3 "B.Mask" user "Board Geometry/Soldermask Bottom")
		(17 "Dwgs.User" user "User.Drawings")
		(19 "Cmts.User" user "User.Comments")
		(21 "Eco1.User" user "User.Eco1")
		(23 "Eco2.User" user "User.Eco2")
		(25 "Edge.Cuts" user "Board Geometry/Outline")
		(27 "Margin" user)
		(31 "F.CrtYd" user "Package Geometry/Place Bound Top")
		(29 "B.CrtYd" user "Package Geometry/Place Bound Bottom")
		(35 "F.Fab" user "Ref Des/Assembly Top")
		(33 "B.Fab" user "Ref Des/Assembly Bottom")
	)
	(footprint ""
		(layer "F.Cu")
		(at 223.875854 -430.2379 -90)
		(property "Reference" "PR56"
			(at 0 0 270)
			(layer "F.SilkS")
			(hide yes)
			(effects
				(font
					(size 1.27 1.27)
				)
			)
		)
		(property "Value" "22K1R3F-GP"
			(at -0.0254 -2.5146 270)
			(unlocked yes)
			(layer "F.Fab")
			(hide yes)
			(effects
				(font
					(size 1.016 1.016)
					(thickness 0.1524)
				)
			)
		)
		(property "Device Type" "R603H22"
			(at -0.0254 -4.0386 270)
			(unlocked yes)
			(layer "F.Fab")
			(hide yes)
			(effects
				(font
					(size 1.016 1.016)
					(thickness 0.1524)
				)
			)
		)
		(duplicate_pad_numbers_are_jumpers no)
		(fp_line
			(start -0.4826 0)
			(end -0.2032 0)
			(stroke
				(width 0.2032)
				(type default)
			)
			(layer "F.SilkS")
		)
		(fp_line
			(start 0.2032 0)
			(end 0.4826 0)
			(stroke
				(width 0.2032)
				(type default)
			)
			(layer "F.SilkS")
		)
		(fp_rect
			(start -0.5842 1.3335)
			(end 0.5842 -1.3335)
			(stroke
				(width 0)
				(type default)
			)
			(fill no)
			(layer "F.CrtYd")
		)
		(fp_rect
			(start -0.5842 1.3335)
			(end 0.5842 -1.3335)
			(stroke
				(width 0)
				(type default)
			)
			(fill no)
			(layer "F.Fab")
		)
		(pad "1" smd custom
			(at 0 -0.762 270)
			(size 0.2159 0.2159)
			(layers "F.Cu" "F.Mask" "F.Paste")
			(net "P3V3_FB")
			(options
				(clearance outline)
				(anchor circle)
			)
			(primitives
				(gr_poly
					(pts
						(arc
							(start -0.3302 -0.4318)
							(mid -0.402042 -0.402042)
							(end -0.4318 -0.3302)
						)
						(arc
							(start -0.4318 0.3302)
							(mid -0.402042 0.402042)
							(end -0.3302 0.4318)
						)
						(arc
							(start 0.3302 0.4318)
							(mid 0.402042 0.402042)
							(end 0.4318 0.3302)
						)
						(arc
							(start 0.4318 -0.3302)
							(mid 0.402042 -0.402042)
							(end 0.3302 -0.4318)
						)
					)
					(width 0)
					(fill yes)
				)
			)
		)
		(pad "2" smd custom
			(at 0 0.762 270)
			(size 0.2159 0.2159)
			(layers "F.Cu" "F.Mask" "F.Paste")
			(net "GND")
			(options
				(clearance outline)
				(anchor circle)
			)
			(primitives
				(gr_poly
					(pts
						(arc
							(start -0.3302 -0.4318)
							(mid -0.402042 -0.402042)
							(end -0.4318 -0.3302)
						)
						(arc
							(start -0.4318 0.3302)
							(mid -0.402042 0.402042)
							(end -0.3302 0.4318)
						)
						(arc
							(start 0.3302 0.4318)
							(mid 0.402042 0.402042)
							(end 0.4318 0.3302)
						)
						(arc
							(start 0.4318 -0.3302)
							(mid 0.402042 -0.402042)
							(end 0.3302 -0.4318)
						)
					)
					(width 0)
					(fill yes)
				)
			)
		)
	)
	(footprint ""
		(layer "F.Cu")
		(at 215.137746 -33.0327 180)
		(property "Reference" "PC11"
			(at 0 0 180)
			(layer "F.SilkS")
			(hide yes)
			(effects
				(font
					(size 1.27 1.27)
				)
			)
		)
		(property "Value" "SC10U16V6KX-2GP"
			(at -0.0762 -5.1308 180)
			(unlocked yes)
			(layer "F.Fab")
			(hide yes)
			(effects
				(font
					(size 1.016 1.016)
					(thickness 0.1524)
				)
			)
		)
		(property "Device Type" "C1206H71"
			(at -0.127 -6.6548 180)
			(unlocked yes)
			(layer "F.Fab")
			(hide yes)
			(effects
				(font
					(size 1.016 1.016)
					(thickness 0.1524)
				)
			)
		)
		(duplicate_pad_numbers_are_jumpers no)
		(fp_line
			(start 1.016 2.2352)
			(end -1.016 2.2352)
			(stroke
				(width 0.1524)
				(type default)
			)
			(layer "F.SilkS")
		)
		(fp_line
			(start 1.016 0.8382)
			(end 1.016 2.2352)
			(stroke
				(width 0.1524)
				(type default)
			)
			(layer "F.SilkS")
		)
		(fp_line
			(start 1.016 -2.2352)
			(end 1.016 -0.8382)
			(stroke
				(width 0.1524)
				(type default)
			)
			(layer "F.SilkS")
		)
		(fp_line
			(start -1.016 2.2352)
			(end -1.016 0.8382)
			(stroke
				(width 0.1524)
				(type default)
			)
			(layer "F.SilkS")
		)
		(fp_line
			(start -1.016 -0.8382)
			(end -1.016 -2.2352)
			(stroke
				(width 0.1524)
				(type default)
			)
			(layer "F.SilkS")
		)
		(fp_line
			(start -1.016 -2.2352)
			(end 1.016 -2.2352)
			(stroke
				(width 0.1524)
				(type default)
			)
			(layer "F.SilkS")
		)
		(fp_rect
			(start -1.0922 2.3114)
			(end 1.0922 -2.3114)
			(stroke
				(width 0)
				(type default)
			)
			(fill no)
			(layer "F.CrtYd")
		)
		(fp_poly
			(pts
				(xy 1.0922 -2.3114) (xy 1.0922 2.3114) (xy -1.0922 2.3114) (xy -1.0922 -2.3114)
			)
			(stroke
				(width 0)
				(type default)
			)
			(fill no)
			(layer "F.Fab")
		)
		(pad "1" smd rect
			(at 0 -1.397 180)
			(size 1.651 1.27)
			(layers "F.Cu" "F.Mask" "F.Paste")
			(net "P5VA")
		)
		(pad "2" smd rect
			(at 0 1.397 180)
			(size 1.651 1.27)
			(layers "F.Cu" "F.Mask" "F.Paste")
			(net "GND")
		)
	)
	(footprint ""
		(layer "F.Cu")
		(at 68.999608 -479.999802)
		(property "Reference" "H12"
			(at 0 0 0)
			(layer "F.SilkS")
			(hide yes)
			(effects
				(font
					(size 1.27 1.27)
				)
			)
		)
		(property "Value" "HOLE315R140"
			(at 0 -7.5692 0)
			(unlocked yes)
			(layer "F.Fab")
			(hide yes)
			(effects
				(font
					(size 1.016 1.016)
					(thickness 0.1524)
				)
			)
		)
		(property "Device Type" "HOLE315R140"
			(at 0 -9.0932 0)
			(unlocked yes)
			(layer "F.Fab")
			(hide yes)
			(effects
				(font
					(size 1.016 1.016)
					(thickness 0.1524)
				)
			)
		)
		(duplicate_pad_numbers_are_jumpers no)
		(fp_poly
			(pts
				(arc
					(start 4.3053 0)
					(mid -4.3053 0)
					(end 4.3053 0)
				)
			)
			(stroke
				(width 0)
				(type default)
			)
			(fill no)
			(layer "F.CrtYd")
		)
		(fp_poly
			(pts
				(arc
					(start 4.3053 0)
					(mid -4.3053 0)
					(end 4.3053 0)
				)
			)
			(stroke
				(width 0)
				(type default)
			)
			(fill no)
			(layer "F.Fab")
		)
		(pad "1" thru_hole circle
			(at 0.00127 0.00127)
			(size 8.001 8.001)
			(drill 3.556)
			(layers "*.Cu" "*.Mask")
			(remove_unused_layers no)
			(net "GND")
			(clearance -1.7145)
			(thermal_gap 0.3048)
			(padstack
				(mode front_inner_back)
				(layer "Inner"
					(shape circle)
					(size 3.9624 3.9624)
					(clearance 0.3048)
				)
				(layer "B.Cu"
					(shape circle)
					(size 8.001 8.001)
					(clearance -1.7145)
				)
			)
		)
	)
	(footprint ""
		(layer "F.Cu")
		(at 59.943746 -13.0937 90)
		(property "Reference" "PC22"
			(at 0 0 90)
			(layer "F.SilkS")
			(hide yes)
			(effects
				(font
					(size 1.27 1.27)
				)
			)
		)
		(property "Value" "SC22U25V5MX-GP"
			(at -0.0762 -6.1214 90)
			(unlocked yes)
			(layer "F.Fab")
			(hide yes)
			(effects
				(font
					(size 1.016 1.016)
					(thickness 0.1524)
				)
			)
		)
		(property "Device Type" "C805H58"
			(at -0.0762 -8.1534 90)
			(unlocked yes)
			(layer "F.Fab")
			(hide yes)
			(effects
				(font
					(size 1.016 1.016)
					(thickness 0.1524)
				)
			)
		)
		(duplicate_pad_numbers_are_jumpers no)
		(fp_line
			(start 0.635 0)
			(end -0.635 0)
			(stroke
				(width 0.508)
				(type default)
			)
			(layer "F.SilkS")
		)
		(fp_rect
			(start -0.9652 1.778)
			(end 0.9652 -1.778)
			(stroke
				(width 0)
				(type default)
			)
			(fill no)
			(layer "F.CrtYd")
		)
		(fp_poly
			(pts
				(xy -0.9652 -1.778) (xy 0.9652 -1.778) (xy 0.9652 1.778) (xy -0.9652 1.778)
			)
			(stroke
				(width 0)
				(type default)
			)
			(fill no)
			(layer "F.Fab")
		)
		(pad "1" smd rect
			(at 0 -0.9652 90)
			(size 1.397 1.143)
			(layers "F.Cu" "F.Mask" "F.Paste")
			(net "P5VB_12VIN")
		)
		(pad "2" smd rect
			(at 0 0.9652 90)
			(size 1.397 1.143)
			(layers "F.Cu" "F.Mask" "F.Paste")
			(net "GND")
		)
	)
	(footprint ""
		(layer "F.Cu")
		(at 230.267256 -452.529702 90)
		(property "Reference" "R103"
			(at 0 0 90)
			(layer "F.SilkS")
			(hide yes)
			(effects
				(font
					(size 1.27 1.27)
				)
			)
		)
		(property "Value" "0R2J-2-GP"
			(at 0.064008 -3.993896 90)
			(unlocked yes)
			(layer "F.Fab")
			(hide yes)
			(effects
				(font
					(size 1.016 1.016)
					(thickness 0.1524)
				)
			)
		)
		(property "Device Type" "R402H16"
			(at 0.064008 -5.517896 90)
			(unlocked yes)
			(layer "F.Fab")
			(hide yes)
			(effects
				(font
					(size 1.016 1.016)
					(thickness 0.1524)
				)
			)
		)
		(duplicate_pad_numbers_are_jumpers no)
		(fp_line
			(start 0.508 -0.9398)
			(end -0.508 -0.9398)
			(stroke
				(width 0.1524)
				(type default)
			)
			(layer "F.SilkS")
		)
		(fp_line
			(start -0.508 -0.9398)
			(end -0.508 0.9398)
			(stroke
				(width 0.1524)
				(type default)
			)
			(layer "F.SilkS")
		)
		(fp_rect
			(start -0.508 0.9398)
			(end 0.508 -0.9398)
			(stroke
				(width 0)
				(type default)
			)
			(fill no)
			(layer "F.CrtYd")
		)
		(fp_rect
			(start -0.508 0.9398)
			(end 0.508 -0.9398)
			(stroke
				(width 0)
				(type default)
			)
			(fill no)
			(layer "F.Fab")
		)
		(pad "1" smd custom
			(at 0 -0.4445 90)
			(size 0.1397 0.1397)
			(layers "F.Cu" "F.Mask" "F.Paste")
			(net "DRV_ACT_NET0")
			(options
				(clearance outline)
				(anchor circle)
			)
			(primitives
				(gr_poly
					(pts
						(arc
							(start -0.1778 -0.2794)
							(mid -0.249642 -0.249642)
							(end -0.2794 -0.1778)
						)
						(arc
							(start -0.2794 0.1778)
							(mid -0.249642 0.249642)
							(end -0.1778 0.2794)
						)
						(arc
							(start 0.1778 0.2794)
							(mid 0.249642 0.249642)
							(end 0.2794 0.1778)
						)
						(arc
							(start 0.2794 -0.1778)
							(mid 0.249642 -0.249642)
							(end 0.1778 -0.2794)
						)
					)
					(width 0)
					(fill yes)
				)
			)
		)
		(pad "2" smd custom
			(at 0 0.4445 90)
			(size 0.1397 0.1397)
			(layers "F.Cu" "F.Mask" "F.Paste")
			(net "DRIVE_ACT_0")
			(options
				(clearance outline)
				(anchor circle)
			)
			(primitives
				(gr_poly
					(pts
						(arc
							(start -0.1778 -0.2794)
							(mid -0.249642 -0.249642)
							(end -0.2794 -0.1778)
						)
						(arc
							(start -0.2794 0.1778)
							(mid -0.249642 0.249642)
							(end -0.1778 0.2794)
						)
						(arc
							(start 0.1778 0.2794)
							(mid 0.249642 0.249642)
							(end 0.2794 0.1778)
						)
						(arc
							(start 0.2794 -0.1778)
							(mid 0.249642 -0.249642)
							(end 0.1778 -0.2794)
						)
					)
					(width 0)
					(fill yes)
				)
			)
		)
	)
	(footprint ""
		(layer "F.Cu")
		(at 200.724262 -389.224012)
		(property "Reference" "U4"
			(at 0 0 0)
			(layer "F.SilkS")
			(hide yes)
			(effects
				(font
					(size 1.27 1.27)
				)
			)
		)
		(property "Value" "74LVC1G08GW-1-GP"
			(at -2.3368 -8.6868 0)
			(unlocked yes)
			(layer "F.Fab")
			(hide yes)
			(effects
				(font
					(size 1.016 1.016)
					(thickness 0.1524)
				)
			)
		)
		(property "Device Type" "SC70-5H44"
			(at -2.3114 -10.414 0)
			(unlocked yes)
			(layer "F.Fab")
			(hide yes)
			(effects
				(font
					(size 1.016 1.016)
					(thickness 0.1524)
				)
			)
		)
		(duplicate_pad_numbers_are_jumpers no)
		(fp_line
			(start -1.27 -1.7018)
			(end 1.27 -1.7018)
			(stroke
				(width 0.1524)
				(type default)
			)
			(layer "F.SilkS")
		)
		(fp_line
			(start -1.27 1.7018)
			(end -1.27 -1.7018)
			(stroke
				(width 0.1524)
				(type default)
			)
			(layer "F.SilkS")
		)
		(fp_line
			(start 0.6604 -1.8034)
			(end 1.3843 -1.8034)
			(stroke
				(width 0.3302)
				(type default)
			)
			(layer "F.SilkS")
		)
		(fp_line
			(start 1.27 -1.7018)
			(end 1.27 1.7018)
			(stroke
				(width 0.1524)
				(type default)
			)
			(layer "F.SilkS")
		)
		(fp_line
			(start 1.27 1.7018)
			(end -1.27 1.7018)
			(stroke
				(width 0.1524)
				(type default)
			)
			(layer "F.SilkS")
		)
		(fp_line
			(start 1.3843 -1.8034)
			(end 1.3843 -1.1176)
			(stroke
				(width 0.3302)
				(type default)
			)
			(layer "F.SilkS")
		)
		(fp_rect
			(start -1.524 1.9558)
			(end 1.524 -1.9558)
			(stroke
				(width 0)
				(type default)
			)
			(fill no)
			(layer "F.CrtYd")
		)
		(fp_poly
			(pts
				(xy -1.524 -1.9558) (xy 1.524 -1.9558) (xy 1.524 1.9558) (xy -1.524 1.9558)
			)
			(stroke
				(width 0)
				(type default)
			)
			(fill no)
			(layer "F.Fab")
		)
		(pad "1" smd rect
			(at 0.65024 -0.8255)
			(size 0.4064 1.2192)
			(layers "F.Cu" "F.Mask" "F.Paste")
			(net "SAS2X28_B_HDD1_FLT")
		)
		(pad "2" smd rect
			(at 0 -0.8255)
			(size 0.4064 1.2192)
			(layers "F.Cu" "F.Mask" "F.Paste")
			(net "SAS2X28_A_HDD1_FLT")
		)
		(pad "3" smd rect
			(at -0.65024 -0.8255)
			(size 0.4064 1.2192)
			(layers "F.Cu" "F.Mask" "F.Paste")
			(net "GND")
		)
		(pad "4" smd rect
			(at -0.65024 0.8255)
			(size 0.4064 1.2192)
			(layers "F.Cu" "F.Mask" "F.Paste")
			(net "FLT_HDD1_DRIVE")
		)
		(pad "5" smd rect
			(at 0.65024 0.8255)
			(size 0.4064 1.2192)
			(layers "F.Cu" "F.Mask" "F.Paste")
			(net "P3V3")
		)
	)
	(footprint ""
		(layer "F.Cu")
		(at 45.085 -323.85)
		(property "Reference" "C375"
			(at 0 0 0)
			(layer "F.SilkS")
			(hide yes)
			(effects
				(font
					(size 1.27 1.27)
				)
			)
		)
		(property "Value" "SCD033U25V2KX-GP"
			(at 1.1811 -2.7051 0)
			(unlocked yes)
			(layer "F.Fab")
			(hide yes)
			(effects
				(font
					(size 1.016 1.016)
					(thickness 0.1524)
				)
			)
		)
		(property "Device Type" "C402H22"
			(at 1.1811 -4.2291 0)
			(unlocked yes)
			(layer "F.Fab")
			(hide yes)
			(effects
				(font
					(size 1.016 1.016)
					(thickness 0.1524)
				)
			)
		)
		(duplicate_pad_numbers_are_jumpers no)
		(fp_rect
			(start -0.4318 0.9525)
			(end 0.4318 -0.9525)
			(stroke
				(width 0)
				(type default)
			)
			(fill no)
			(layer "F.CrtYd")
		)
		(fp_rect
			(start -0.4318 0.9525)
			(end 0.4318 -0.9525)
			(stroke
				(width 0)
				(type default)
			)
			(fill no)
			(layer "F.Fab")
		)
		(pad "1" smd custom
			(at 0 -0.4445)
			(size 0.1524 0.1524)
			(layers "F.Cu" "F.Mask" "F.Paste")
			(net "SW_HDD11_P")
			(options
				(clearance outline)
				(anchor circle)
			)
			(primitives
				(gr_poly
					(pts
						(arc
							(start 0.3048 -0.2032)
							(mid 0.275042 -0.275042)
							(end 0.2032 -0.3048)
						)
						(arc
							(start -0.2032 -0.3048)
							(mid -0.275042 -0.275042)
							(end -0.3048 -0.2032)
						)
						(arc
							(start -0.3048 0.2032)
							(mid -0.275042 0.275042)
							(end -0.2032 0.3048)
						)
						(arc
							(start 0.2032 0.3048)
							(mid 0.275042 0.275042)
							(end 0.3048 0.2032)
						)
					)
					(width 0)
					(fill yes)
				)
			)
		)
		(pad "2" smd custom
			(at 0 0.4445)
			(size 0.1524 0.1524)
			(layers "F.Cu" "F.Mask" "F.Paste")
			(net "GND")
			(options
				(clearance outline)
				(anchor circle)
			)
			(primitives
				(gr_poly
					(pts
						(arc
							(start 0.3048 -0.2032)
							(mid 0.275042 -0.275042)
							(end 0.2032 -0.3048)
						)
						(arc
							(start -0.2032 -0.3048)
							(mid -0.275042 -0.275042)
							(end -0.3048 -0.2032)
						)
						(arc
							(start -0.3048 0.2032)
							(mid -0.275042 0.275042)
							(end -0.2032 0.3048)
						)
						(arc
							(start 0.2032 0.3048)
							(mid 0.275042 0.275042)
							(end 0.3048 0.2032)
						)
					)
					(width 0)
					(fill yes)
				)
			)
		)
	)
	(footprint ""
		(layer "F.Cu")
		(at 240.537746 -29.8577 180)
		(property "Reference" "PG1"
			(at 0 0 180)
			(layer "F.SilkS")
			(hide yes)
			(effects
				(font
					(size 1.27 1.27)
				)
			)
		)
		(property "Value" "COPPER-CLOSE-GP-U"
			(at 0.0762 -2.8702 180)
			(unlocked yes)
			(layer "F.Fab")
			(hide yes)
			(effects
				(font
					(size 1.016 1.016)
					(thickness 0.1524)
				)
			)
		)
		(property "Device Type" "CON2C-U"
			(at 0.0762 -4.3942 180)
			(unlocked yes)
			(layer "F.Fab")
			(hide yes)
			(effects
				(font
					(size 1.016 1.016)
					(thickness 0.1524)
				)
			)
		)
		(duplicate_pad_numbers_are_jumpers no)
		(fp_rect
			(start -0.9398 0.9652)
			(end 0.9398 -0.9652)
			(stroke
				(width 0)
				(type default)
			)
			(fill no)
			(layer "F.CrtYd")
		)
		(fp_rect
			(start -0.9398 0.9652)
			(end 0.9398 -0.9652)
			(stroke
				(width 0)
				(type default)
			)
			(fill no)
			(layer "F.Fab")
		)
		(pad "1" smd custom
			(at 0 -0.5334 180)
			(size 0.17145 0.17145)
			(layers "F.Cu" "F.Mask" "F.Paste")
			(net "P5VA_AGND")
			(options
				(clearance outline)
				(anchor circle)
			)
			(primitives
				(gr_poly
					(pts
						(xy -0.127 0.3429) (xy -0.127 0.1651) (xy -0.635 -0.3429) (xy 0.635 -0.3429) (xy 0.127 0.1651)
						(xy 0.127 0.3429)
					)
					(width 0)
					(fill yes)
				)
			)
		)
		(pad "2" smd custom
			(at 0 0.5334 180)
			(size 0.17145 0.17145)
			(layers "F.Cu" "F.Mask" "F.Paste")
			(net "GND")
			(options
				(clearance outline)
				(anchor circle)
			)
			(primitives
				(gr_poly
					(pts
						(xy -0.635 0.3429) (xy -0.127 -0.1651) (xy -0.127 -0.3429) (xy 0.127 -0.3429) (xy 0.127 -0.1651)
						(xy 0.635 0.3429)
					)
					(width 0)
					(fill yes)
				)
			)
		)
	)
)
